(kicad_pcb
	(version 20260206)
	(generator "pcbnew")
	(generator_version "10.0")
	(general
		(thickness 1.6)
		(legacy_teardrops no)
	)
	(paper "A4")
	(title_block
		(title "04192023_DAF0TMB3IC0_F0TG_MB_C_brd_V02_OCP.brd")
		(comment 1 "Grand Teton / footprints 5764-5771 of 8354")
	)
	(layers
		(0 "F.Cu" signal "TOP")
		(4 "In1.Cu" signal "GND")
		(6 "In2.Cu" signal "IN1")
		(8 "In3.Cu" signal "GND1")
		(10 "In4.Cu" signal "IN2")
		(12 "In5.Cu" signal "GND2")
		(14 "In6.Cu" signal "IN3")
		(16 "In7.Cu" signal "GND3")
		(18 "In8.Cu" signal "VCC")
		(20 "In9.Cu" signal "VCC1")
		(22 "In10.Cu" signal "GND4")
		(24 "In11.Cu" signal "IN4")
		(26 "In12.Cu" signal "GND5")
		(28 "In13.Cu" signal "IN5")
		(30 "In14.Cu" signal "GND6")
		(32 "In15.Cu" signal "IN6")
		(34 "In16.Cu" signal "GND7")
		(2 "B.Cu" signal "BOTTOM")
		(9 "F.Adhes" user "F.Adhesive")
		(11 "B.Adhes" user "B.Adhesive")
		(13 "F.Paste" user "Package Geometry/Pastemask Top")
		(15 "B.Paste" user "Package Geometry/Pastemask Bottom")
		(5 "F.SilkS" user "Ref Des/Silkscreen Top")
		(7 "B.SilkS" user "Ref Des/Silkscreen Bottom")
		(1 "F.Mask" user "Board Geometry/Soldermask Top")
		(3 "B.Mask" user "Board Geometry/Soldermask Bottom")
		(17 "Dwgs.User" user "User.Drawings")
		(19 "Cmts.User" user "User.Comments")
		(21 "Eco1.User" user "User.Eco1")
		(23 "Eco2.User" user "User.Eco2")
		(25 "Edge.Cuts" user "Board Geometry/Outline")
		(27 "Margin" user)
		(31 "F.CrtYd" user "Package Geometry/Place Bound Top")
		(29 "B.CrtYd" user "Package Geometry/Place Bound Bottom")
		(35 "F.Fab" user "Ref Des/Assembly Top")
		(33 "B.Fab" user "Ref Des/Assembly Bottom")
	)
	(footprint ""
		(layer "B.Cu")
		(at 371.551454 -259.729986)
		(property "Reference" "C2542"
			(at 0 0 0)
			(layer "B.SilkS")
			(hide yes)
			(effects
				(font
					(size 1.27 1.27)
				)
				(justify mirror)
			)
		)
		(property "Value" ""
			(at 0 0 0)
			(layer "B.Fab")
			(effects
				(font
					(size 1.27 1.27)
				)
				(justify mirror)
			)
		)
		(duplicate_pad_numbers_are_jumpers no)
		(fp_line
			(start -0.7874 -0.4064)
			(end -0.7874 0.4064)
			(stroke
				(width 0.1524)
				(type default)
			)
			(layer "B.SilkS")
		)
		(fp_line
			(start -0.7874 0.4064)
			(end 0.7874 0.4064)
			(stroke
				(width 0.1524)
				(type default)
			)
			(layer "B.SilkS")
		)
		(fp_line
			(start 0.7874 -0.4064)
			(end -0.7874 -0.4064)
			(stroke
				(width 0.1524)
				(type default)
			)
			(layer "B.SilkS")
		)
		(fp_line
			(start 0.7874 0.4064)
			(end 0.7874 -0.4064)
			(stroke
				(width 0.1524)
				(type default)
			)
			(layer "B.SilkS")
		)
		(fp_line
			(start -0.67945 -0.3048)
			(end -0.67945 0.3048)
			(stroke
				(width 0.1)
				(type default)
			)
			(layer "B.Fab")
		)
		(fp_line
			(start -0.67945 0.3048)
			(end -0.120396 0.3048)
			(stroke
				(width 0.1)
				(type default)
			)
			(layer "B.Fab")
		)
		(fp_line
			(start -0.12065 -0.3048)
			(end -0.67945 -0.3048)
			(stroke
				(width 0.1)
				(type default)
			)
			(layer "B.Fab")
		)
		(fp_line
			(start -0.12065 -0.2794)
			(end -0.12065 -0.3048)
			(stroke
				(width 0.1)
				(type default)
			)
			(layer "B.Fab")
		)
		(fp_line
			(start -0.120396 0.2794)
			(end 0.12065 0.2794)
			(stroke
				(width 0.1)
				(type default)
			)
			(layer "B.Fab")
		)
		(fp_line
			(start -0.120396 0.3048)
			(end -0.120396 0.2794)
			(stroke
				(width 0.1)
				(type default)
			)
			(layer "B.Fab")
		)
		(fp_line
			(start 0.12065 -0.305054)
			(end 0.12065 -0.2794)
			(stroke
				(width 0.1)
				(type default)
			)
			(layer "B.Fab")
		)
		(fp_line
			(start 0.12065 -0.2794)
			(end -0.12065 -0.2794)
			(stroke
				(width 0.1)
				(type default)
			)
			(layer "B.Fab")
		)
		(fp_line
			(start 0.12065 0.2794)
			(end 0.12065 0.3048)
			(stroke
				(width 0.1)
				(type default)
			)
			(layer "B.Fab")
		)
		(fp_line
			(start 0.12065 0.3048)
			(end 0.67945 0.3048)
			(stroke
				(width 0.1)
				(type default)
			)
			(layer "B.Fab")
		)
		(fp_line
			(start 0.67945 -0.305054)
			(end 0.12065 -0.305054)
			(stroke
				(width 0.1)
				(type default)
			)
			(layer "B.Fab")
		)
		(fp_line
			(start 0.67945 0.3048)
			(end 0.67945 -0.305054)
			(stroke
				(width 0.1)
				(type default)
			)
			(layer "B.Fab")
		)
		(pad "1" smd circle
			(at 0.40005 0 180)
			(size 0 0)
			(layers "B.Cu" "B.Mask" "B.Paste")
			(net "PVDDCR_SOC_P0")
		)
		(pad "2" smd circle
			(at -0.40005 0 180)
			(size 0 0)
			(layers "B.Cu" "B.Mask" "B.Paste")
			(net "GND")
		)
	)
	(footprint ""
		(layer "B.Cu")
		(at 123.611386 -250.892564)
		(property "Reference" "C2312"
			(at 0 0 0)
			(layer "B.SilkS")
			(hide yes)
			(effects
				(font
					(size 1.27 1.27)
				)
				(justify mirror)
			)
		)
		(property "Value" ""
			(at 0 0 0)
			(layer "B.Fab")
			(effects
				(font
					(size 1.27 1.27)
				)
				(justify mirror)
			)
		)
		(duplicate_pad_numbers_are_jumpers no)
		(fp_line
			(start -0.7874 -0.4064)
			(end -0.7874 0.4064)
			(stroke
				(width 0.1524)
				(type default)
			)
			(layer "B.SilkS")
		)
		(fp_line
			(start -0.7874 0.4064)
			(end 0.7874 0.4064)
			(stroke
				(width 0.1524)
				(type default)
			)
			(layer "B.SilkS")
		)
		(fp_line
			(start 0.7874 -0.4064)
			(end -0.7874 -0.4064)
			(stroke
				(width 0.1524)
				(type default)
			)
			(layer "B.SilkS")
		)
		(fp_line
			(start 0.7874 0.4064)
			(end 0.7874 -0.4064)
			(stroke
				(width 0.1524)
				(type default)
			)
			(layer "B.SilkS")
		)
		(fp_line
			(start -0.67945 -0.3048)
			(end -0.67945 0.3048)
			(stroke
				(width 0.1)
				(type default)
			)
			(layer "B.Fab")
		)
		(fp_line
			(start -0.67945 0.3048)
			(end -0.120396 0.3048)
			(stroke
				(width 0.1)
				(type default)
			)
			(layer "B.Fab")
		)
		(fp_line
			(start -0.12065 -0.3048)
			(end -0.67945 -0.3048)
			(stroke
				(width 0.1)
				(type default)
			)
			(layer "B.Fab")
		)
		(fp_line
			(start -0.12065 -0.2794)
			(end -0.12065 -0.3048)
			(stroke
				(width 0.1)
				(type default)
			)
			(layer "B.Fab")
		)
		(fp_line
			(start -0.120396 0.2794)
			(end 0.12065 0.2794)
			(stroke
				(width 0.1)
				(type default)
			)
			(layer "B.Fab")
		)
		(fp_line
			(start -0.120396 0.3048)
			(end -0.120396 0.2794)
			(stroke
				(width 0.1)
				(type default)
			)
			(layer "B.Fab")
		)
		(fp_line
			(start 0.12065 -0.305054)
			(end 0.12065 -0.2794)
			(stroke
				(width 0.1)
				(type default)
			)
			(layer "B.Fab")
		)
		(fp_line
			(start 0.12065 -0.2794)
			(end -0.12065 -0.2794)
			(stroke
				(width 0.1)
				(type default)
			)
			(layer "B.Fab")
		)
		(fp_line
			(start 0.12065 0.2794)
			(end 0.12065 0.3048)
			(stroke
				(width 0.1)
				(type default)
			)
			(layer "B.Fab")
		)
		(fp_line
			(start 0.12065 0.3048)
			(end 0.67945 0.3048)
			(stroke
				(width 0.1)
				(type default)
			)
			(layer "B.Fab")
		)
		(fp_line
			(start 0.67945 -0.305054)
			(end 0.12065 -0.305054)
			(stroke
				(width 0.1)
				(type default)
			)
			(layer "B.Fab")
		)
		(fp_line
			(start 0.67945 0.3048)
			(end 0.67945 -0.305054)
			(stroke
				(width 0.1)
				(type default)
			)
			(layer "B.Fab")
		)
		(pad "1" smd circle
			(at 0.40005 0 180)
			(size 0 0)
			(layers "B.Cu" "B.Mask" "B.Paste")
			(net "PVDDCR_CPU0_P1")
		)
		(pad "2" smd circle
			(at -0.40005 0 180)
			(size 0 0)
			(layers "B.Cu" "B.Mask" "B.Paste")
			(net "GND")
		)
	)
	(footprint ""
		(layer "B.Cu")
		(at 72.462644 -389.673084 90)
		(property "Reference" "C323"
			(at 0 0 90)
			(layer "B.SilkS")
			(hide yes)
			(effects
				(font
					(size 1.27 1.27)
				)
				(justify mirror)
			)
		)
		(property "Value" ""
			(at 0 0 90)
			(layer "B.Fab")
			(effects
				(font
					(size 1.27 1.27)
				)
				(justify mirror)
			)
		)
		(duplicate_pad_numbers_are_jumpers no)
		(fp_line
			(start 1.524 -0.762)
			(end -1.524 -0.762)
			(stroke
				(width 0.1524)
				(type default)
			)
			(layer "B.SilkS")
		)
		(fp_line
			(start -1.524 -0.762)
			(end -1.524 0.762)
			(stroke
				(width 0.1524)
				(type default)
			)
			(layer "B.SilkS")
		)
		(fp_line
			(start 1.524 0.762)
			(end 1.524 -0.762)
			(stroke
				(width 0.1524)
				(type default)
			)
			(layer "B.SilkS")
		)
		(fp_line
			(start -1.524 0.762)
			(end 1.524 0.762)
			(stroke
				(width 0.1524)
				(type default)
			)
			(layer "B.SilkS")
		)
		(fp_line
			(start 1.1049 -0.724916)
			(end 1.1049 0.724916)
			(stroke
				(width 0.1)
				(type default)
			)
			(layer "B.Fab")
		)
		(fp_line
			(start -1.1049 -0.724916)
			(end 1.1049 -0.724916)
			(stroke
				(width 0.1)
				(type default)
			)
			(layer "B.Fab")
		)
		(fp_line
			(start 1.1049 0.724916)
			(end -1.1049 0.724916)
			(stroke
				(width 0.1)
				(type default)
			)
			(layer "B.Fab")
		)
		(fp_line
			(start -1.1049 0.724916)
			(end -1.1049 -0.724916)
			(stroke
				(width 0.1)
				(type default)
			)
			(layer "B.Fab")
		)
		(pad "1" smd rect
			(at 0.889 0 90)
			(size 1.016 1.27)
			(layers "B.Cu" "B.Mask" "B.Paste")
			(net "P0V9_CPU1_RT_2D")
		)
		(pad "2" smd rect
			(at -0.889 0 90)
			(size 1.016 1.27)
			(layers "B.Cu" "B.Mask" "B.Paste")
			(net "GND")
		)
	)
	(footprint ""
		(layer "B.Cu")
		(at 110.365794 -385.58216 180)
		(property "Reference" "R919"
			(at 0 0 0)
			(layer "B.SilkS")
			(hide yes)
			(effects
				(font
					(size 1.27 1.27)
				)
				(justify mirror)
			)
		)
		(property "Value" ""
			(at 0 0 0)
			(layer "B.Fab")
			(effects
				(font
					(size 1.27 1.27)
				)
				(justify mirror)
			)
		)
		(duplicate_pad_numbers_are_jumpers no)
		(fp_line
			(start 0.32512 0.175006)
			(end 0.32512 -0.175006)
			(stroke
				(width 0.1)
				(type default)
			)
			(layer "B.Fab")
		)
		(fp_line
			(start 0.32512 -0.175006)
			(end -0.32512 -0.175006)
			(stroke
				(width 0.1)
				(type default)
			)
			(layer "B.Fab")
		)
		(fp_line
			(start -0.32512 0.175006)
			(end 0.32512 0.175006)
			(stroke
				(width 0.1)
				(type default)
			)
			(layer "B.Fab")
		)
		(fp_line
			(start -0.32512 -0.175006)
			(end -0.32512 0.175006)
			(stroke
				(width 0.1)
				(type default)
			)
			(layer "B.Fab")
		)
		(pad "1" smd rect
			(at 0.2667 0)
			(size 0.3048 0.381)
			(layers "B.Cu" "B.Mask" "B.Paste")
			(net "TEST0_RT_CPU1_P3")
		)
		(pad "2" smd rect
			(at -0.2667 0 180)
			(size 0.3048 0.381)
			(layers "B.Cu" "B.Mask" "B.Paste")
			(net "GND")
		)
	)
	(footprint ""
		(layer "B.Cu")
		(at 231.648 -336.169 -90)
		(property "Reference" "R6767"
			(at 0 0 90)
			(layer "B.SilkS")
			(hide yes)
			(effects
				(font
					(size 1.27 1.27)
				)
				(justify mirror)
			)
		)
		(property "Value" ""
			(at 0 0 90)
			(layer "B.Fab")
			(effects
				(font
					(size 1.27 1.27)
				)
				(justify mirror)
			)
		)
		(duplicate_pad_numbers_are_jumpers no)
		(fp_line
			(start -0.32512 0.175006)
			(end 0.32512 0.175006)
			(stroke
				(width 0.1)
				(type default)
			)
			(layer "B.Fab")
		)
		(fp_line
			(start 0.32512 0.175006)
			(end 0.32512 -0.175006)
			(stroke
				(width 0.1)
				(type default)
			)
			(layer "B.Fab")
		)
		(fp_line
			(start -0.32512 -0.175006)
			(end -0.32512 0.175006)
			(stroke
				(width 0.1)
				(type default)
			)
			(layer "B.Fab")
		)
		(fp_line
			(start 0.32512 -0.175006)
			(end -0.32512 -0.175006)
			(stroke
				(width 0.1)
				(type default)
			)
			(layer "B.Fab")
		)
		(pad "1" smd rect
			(at 0.2667 0 90)
			(size 0.3048 0.381)
			(layers "B.Cu" "B.Mask" "B.Paste")
			(net "P1V8_CPU0_RT_1D")
		)
		(pad "2" smd rect
			(at -0.2667 0 270)
			(size 0.3048 0.381)
			(layers "B.Cu" "B.Mask" "B.Paste")
			(net "SMB_RT_CPU0_P3_R_SCL")
		)
	)
	(footprint ""
		(layer "B.Cu")
		(at 181.57063 -133.838696 -90)
		(property "Reference" "R1285"
			(at 0 0 90)
			(layer "B.SilkS")
			(hide yes)
			(effects
				(font
					(size 1.27 1.27)
				)
				(justify mirror)
			)
		)
		(property "Value" ""
			(at 0 0 90)
			(layer "B.Fab")
			(effects
				(font
					(size 1.27 1.27)
				)
				(justify mirror)
			)
		)
		(duplicate_pad_numbers_are_jumpers no)
		(fp_line
			(start -0.7874 0.4064)
			(end 0.7874 0.4064)
			(stroke
				(width 0.1524)
				(type default)
			)
			(layer "B.SilkS")
		)
		(fp_line
			(start 0.7874 0.4064)
			(end 0.7874 -0.4064)
			(stroke
				(width 0.1524)
				(type default)
			)
			(layer "B.SilkS")
		)
		(fp_line
			(start -0.7874 -0.4064)
			(end -0.7874 0.4064)
			(stroke
				(width 0.1524)
				(type default)
			)
			(layer "B.SilkS")
		)
		(fp_line
			(start 0.7874 -0.4064)
			(end -0.7874 -0.4064)
			(stroke
				(width 0.1524)
				(type default)
			)
			(layer "B.SilkS")
		)
		(fp_line
			(start -0.67945 0.3048)
			(end -0.120396 0.3048)
			(stroke
				(width 0.1)
				(type default)
			)
			(layer "B.Fab")
		)
		(fp_line
			(start -0.120396 0.3048)
			(end -0.120396 0.2794)
			(stroke
				(width 0.1)
				(type default)
			)
			(layer "B.Fab")
		)
		(fp_line
			(start 0.12065 0.3048)
			(end 0.67945 0.3048)
			(stroke
				(width 0.1)
				(type default)
			)
			(layer "B.Fab")
		)
		(fp_line
			(start 0.67945 0.3048)
			(end 0.67945 -0.305054)
			(stroke
				(width 0.1)
				(type default)
			)
			(layer "B.Fab")
		)
		(fp_line
			(start -0.120396 0.2794)
			(end 0.12065 0.2794)
			(stroke
				(width 0.1)
				(type default)
			)
			(layer "B.Fab")
		)
		(fp_line
			(start 0.12065 0.2794)
			(end 0.12065 0.3048)
			(stroke
				(width 0.1)
				(type default)
			)
			(layer "B.Fab")
		)
		(fp_line
			(start -0.12065 -0.2794)
			(end -0.12065 -0.3048)
			(stroke
				(width 0.1)
				(type default)
			)
			(layer "B.Fab")
		)
		(fp_line
			(start 0.12065 -0.2794)
			(end -0.12065 -0.2794)
			(stroke
				(width 0.1)
				(type default)
			)
			(layer "B.Fab")
		)
		(fp_line
			(start -0.67945 -0.3048)
			(end -0.67945 0.3048)
			(stroke
				(width 0.1)
				(type default)
			)
			(layer "B.Fab")
		)
		(fp_line
			(start -0.12065 -0.3048)
			(end -0.67945 -0.3048)
			(stroke
				(width 0.1)
				(type default)
			)
			(layer "B.Fab")
		)
		(fp_line
			(start 0.12065 -0.305054)
			(end 0.12065 -0.2794)
			(stroke
				(width 0.1)
				(type default)
			)
			(layer "B.Fab")
		)
		(fp_line
			(start 0.67945 -0.305054)
			(end 0.12065 -0.305054)
			(stroke
				(width 0.1)
				(type default)
			)
			(layer "B.Fab")
		)
		(pad "1" smd circle
			(at 0.40005 0 90)
			(size 0 0)
			(layers "B.Cu" "B.Mask" "B.Paste")
			(net "FM_P1_PCC0_N")
		)
		(pad "2" smd circle
			(at -0.40005 0 90)
			(size 0 0)
			(layers "B.Cu" "B.Mask" "B.Paste")
			(net "PVDD18_S5_P1")
		)
	)
	(footprint ""
		(layer "B.Cu")
		(at 335.932526 -416.899344 90)
		(property "Reference" "C6554"
			(at 0 0 90)
			(layer "B.SilkS")
			(hide yes)
			(effects
				(font
					(size 1.27 1.27)
				)
				(justify mirror)
			)
		)
		(property "Value" ""
			(at 0 0 90)
			(layer "B.Fab")
			(effects
				(font
					(size 1.27 1.27)
				)
				(justify mirror)
			)
		)
		(duplicate_pad_numbers_are_jumpers no)
		(fp_line
			(start 0.299974 -0.150114)
			(end -0.299974 -0.150114)
			(stroke
				(width 0.1)
				(type default)
			)
			(layer "B.Fab")
		)
		(fp_line
			(start -0.299974 -0.150114)
			(end -0.299974 0.150114)
			(stroke
				(width 0.1)
				(type default)
			)
			(layer "B.Fab")
		)
		(fp_line
			(start 0.299974 0.150114)
			(end 0.299974 -0.150114)
			(stroke
				(width 0.1)
				(type default)
			)
			(layer "B.Fab")
		)
		(fp_line
			(start -0.299974 0.150114)
			(end 0.299974 0.150114)
			(stroke
				(width 0.1)
				(type default)
			)
			(layer "B.Fab")
		)
		(pad "1" smd rect
			(at 0.2667 0 270)
			(size 0.3048 0.381)
			(layers "B.Cu" "B.Mask" "B.Paste")
			(net "P5E_CPU0_P1_TX_BUF_C_DN<10>")
		)
		(pad "2" smd rect
			(at -0.2667 0 270)
			(size 0.3048 0.381)
			(layers "B.Cu" "B.Mask" "B.Paste")
			(net "P5E_CPU0_P1_TX_BUF_DN<10>")
		)
	)
	(footprint ""
		(layer "B.Cu")
		(at 296.222928 -337.980528 -90)
		(property "Reference" "PC166_1"
			(at 0 0 90)
			(layer "B.SilkS")
			(hide yes)
			(effects
				(font
					(size 1.27 1.27)
				)
				(justify mirror)
			)
		)
		(property "Value" ""
			(at 0 0 90)
			(layer "B.Fab")
			(effects
				(font
					(size 1.27 1.27)
				)
				(justify mirror)
			)
		)
		(duplicate_pad_numbers_are_jumpers no)
		(fp_line
			(start -1.524 0.762)
			(end 1.524 0.762)
			(stroke
				(width 0.1524)
				(type default)
			)
			(layer "B.SilkS")
		)
		(fp_line
			(start 1.524 0.762)
			(end 1.524 -0.762)
			(stroke
				(width 0.1524)
				(type default)
			)
			(layer "B.SilkS")
		)
		(fp_line
			(start -1.524 -0.762)
			(end -1.524 0.762)
			(stroke
				(width 0.1524)
				(type default)
			)
			(layer "B.SilkS")
		)
		(fp_line
			(start 1.524 -0.762)
			(end -1.524 -0.762)
			(stroke
				(width 0.1524)
				(type default)
			)
			(layer "B.SilkS")
		)
		(fp_line
			(start -1.1049 0.724916)
			(end -1.1049 -0.724916)
			(stroke
				(width 0.1)
				(type default)
			)
			(layer "B.Fab")
		)
		(fp_line
			(start 1.1049 0.724916)
			(end -1.1049 0.724916)
			(stroke
				(width 0.1)
				(type default)
			)
			(layer "B.Fab")
		)
		(fp_line
			(start -1.1049 -0.724916)
			(end 1.1049 -0.724916)
			(stroke
				(width 0.1)
				(type default)
			)
			(layer "B.Fab")
		)
		(fp_line
			(start 1.1049 -0.724916)
			(end 1.1049 0.724916)
			(stroke
				(width 0.1)
				(type default)
			)
			(layer "B.Fab")
		)
		(pad "1" smd rect
			(at 0.889 0 270)
			(size 1.016 1.27)
			(layers "B.Cu" "B.Mask" "B.Paste")
			(net "PVDDIO_P0")
		)
		(pad "2" smd rect
			(at -0.889 0 270)
			(size 1.016 1.27)
			(layers "B.Cu" "B.Mask" "B.Paste")
			(net "GND")
		)
	)
)
